# S9S_MB_2U (Grand Teton) — schematic netlist excerpt (pin names and nets, part order shuffled) for the footprints in the layout excerpt that follows; sources: Cadence DE-HDL packaged netlist, KiCad conversion of 03242023_DA0F0TMBIJ0_F0T_Motherboard_J_brd_V01_OCP.brd

R2232  Q_RES  10K 1% CHIP  pkg 0402LF  page 195 : A = P1V05_PCH_AUX ; B = FAB_REV_ID0
R1148  Q_RES  0 5% CHIP  pkg 0402LF  page 156 : A = HP_LVC3_OCP_V3_1_PRSNT2_N_R ; B = HP_LVC3_OCP_V3_1_PRSNT2_N

(kicad_pcb
	(version 20260206)
	(generator "pcbnew")
	(generator_version "10.0")
	(general
		(thickness 1.6)
		(legacy_teardrops no)
	)
	(paper "A4")
	(title_block
		(title "03242023_DA0F0TMBIJ0_F0T_Motherboard_J_brd_V01_OCP.brd")
		(comment 1 "Grand Teton / footprints 2355-2356 of 6105")
	)
	(layers
		(0 "F.Cu" signal "TOP")
		(4 "In1.Cu" signal "GND")
		(6 "In2.Cu" signal "IN1")
		(8 "In3.Cu" signal "GND1")
		(10 "In4.Cu" signal "IN2")
		(12 "In5.Cu" signal "GND2")
		(14 "In6.Cu" signal "IN3")
		(16 "In7.Cu" signal "GND3")
		(18 "In8.Cu" signal "VCC")
		(20 "In9.Cu" signal "VCC1")
		(22 "In10.Cu" signal "GND4")
		(24 "In11.Cu" signal "IN4")
		(26 "In12.Cu" signal "GND5")
		(28 "In13.Cu" signal "IN5")
		(30 "In14.Cu" signal "GND6")
		(32 "In15.Cu" signal "IN6")
		(34 "In16.Cu" signal "GND7")
		(2 "B.Cu" signal "BOTTOM")
		(9 "F.Adhes" user "F.Adhesive")
		(11 "B.Adhes" user "B.Adhesive")
		(13 "F.Paste" user "Package Geometry/Pastemask Top")
		(15 "B.Paste" user "Package Geometry/Pastemask Bottom")
		(5 "F.SilkS" user "Ref Des/Silkscreen Top")
		(7 "B.SilkS" user "Ref Des/Silkscreen Bottom")
		(1 "F.Mask" user "Board Geometry/Soldermask Top")
		(3 "B.Mask" user "Board Geometry/Soldermask Bottom")
		(17 "Dwgs.User" user "User.Drawings")
		(19 "Cmts.User" user "User.Comments")
		(21 "Eco1.User" user "User.Eco1")
		(23 "Eco2.User" user "User.Eco2")
		(25 "Edge.Cuts" user "Board Geometry/Outline")
		(27 "Margin" user)
		(31 "F.CrtYd" user "Package Geometry/Place Bound Top")
		(29 "B.CrtYd" user "Package Geometry/Place Bound Bottom")
		(35 "F.Fab" user "Ref Des/Assembly Top")
		(33 "B.Fab" user "Ref Des/Assembly Bottom")
	)
	(footprint ""
		(layer "F.Cu")
		(at 461.593946 -108.694728)
		(property "Reference" "R1148"
			(at 0 0 0)
			(layer "F.SilkS")
			(hide yes)
			(effects
				(font
					(size 1.27 1.27)
				)
			)
		)
		(property "Value" ""
			(at 0 0 0)
			(layer "F.Fab")
			(effects
				(font
					(size 1.27 1.27)
				)
			)
		)
		(duplicate_pad_numbers_are_jumpers no)
		(fp_line
			(start -0.7874 -0.4064)
			(end 0.7874 -0.4064)
			(stroke
				(width 0.1524)
				(type default)
			)
			(layer "F.SilkS")
		)
		(fp_line
			(start -0.7874 0.4064)
			(end -0.7874 -0.4064)
			(stroke
				(width 0.1524)
				(type default)
			)
			(layer "F.SilkS")
		)
		(fp_line
			(start 0.7874 -0.4064)
			(end 0.7874 0.4064)
			(stroke
				(width 0.1524)
				(type default)
			)
			(layer "F.SilkS")
		)
		(fp_line
			(start 0.7874 0.4064)
			(end -0.7874 0.4064)
			(stroke
				(width 0.1524)
				(type default)
			)
			(layer "F.SilkS")
		)
		(fp_line
			(start -0.67945 -0.305054)
			(end -0.12065 -0.305054)
			(stroke
				(width 0.1)
				(type default)
			)
			(layer "F.Fab")
		)
		(fp_line
			(start -0.67945 0.3048)
			(end -0.67945 -0.305054)
			(stroke
				(width 0.1)
				(type default)
			)
			(layer "F.Fab")
		)
		(fp_line
			(start -0.12065 -0.305054)
			(end -0.12065 -0.2794)
			(stroke
				(width 0.1)
				(type default)
			)
			(layer "F.Fab")
		)
		(fp_line
			(start -0.12065 -0.2794)
			(end 0.12065 -0.2794)
			(stroke
				(width 0.1)
				(type default)
			)
			(layer "F.Fab")
		)
		(fp_line
			(start -0.12065 0.2794)
			(end -0.12065 0.3048)
			(stroke
				(width 0.1)
				(type default)
			)
			(layer "F.Fab")
		)
		(fp_line
			(start -0.12065 0.3048)
			(end -0.67945 0.3048)
			(stroke
				(width 0.1)
				(type default)
			)
			(layer "F.Fab")
		)
		(fp_line
			(start 0.120396 0.2794)
			(end -0.12065 0.2794)
			(stroke
				(width 0.1)
				(type default)
			)
			(layer "F.Fab")
		)
		(fp_line
			(start 0.120396 0.3048)
			(end 0.120396 0.2794)
			(stroke
				(width 0.1)
				(type default)
			)
			(layer "F.Fab")
		)
		(fp_line
			(start 0.12065 -0.3048)
			(end 0.67945 -0.3048)
			(stroke
				(width 0.1)
				(type default)
			)
			(layer "F.Fab")
		)
		(fp_line
			(start 0.12065 -0.2794)
			(end 0.12065 -0.3048)
			(stroke
				(width 0.1)
				(type default)
			)
			(layer "F.Fab")
		)
		(fp_line
			(start 0.67945 -0.3048)
			(end 0.67945 0.3048)
			(stroke
				(width 0.1)
				(type default)
			)
			(layer "F.Fab")
		)
		(fp_line
			(start 0.67945 0.3048)
			(end 0.120396 0.3048)
			(stroke
				(width 0.1)
				(type default)
			)
			(layer "F.Fab")
		)
		(pad "1" smd circle
			(at -0.40005 0)
			(size 0 0)
			(layers "F.Cu" "F.Mask" "F.Paste")
			(net "HP_LVC3_OCP_V3_1_PRSNT2_N_R")
		)
		(pad "2" smd circle
			(at 0.40005 0)
			(size 0 0)
			(layers "F.Cu" "F.Mask" "F.Paste")
			(net "HP_LVC3_OCP_V3_1_PRSNT2_N")
		)
	)
	(footprint ""
		(layer "F.Cu")
		(at 299.02023 -51.352196)
		(property "Reference" "R2232"
			(at 0 0 0)
			(layer "F.SilkS")
			(hide yes)
			(effects
				(font
					(size 1.27 1.27)
				)
			)
		)
		(property "Value" ""
			(at 0 0 0)
			(layer "F.Fab")
			(effects
				(font
					(size 1.27 1.27)
				)
			)
		)
		(duplicate_pad_numbers_are_jumpers no)
		(fp_line
			(start -0.7874 -0.4064)
			(end 0.7874 -0.4064)
			(stroke
				(width 0.1524)
				(type default)
			)
			(layer "F.SilkS")
		)
		(fp_line
			(start -0.7874 0.4064)
			(end -0.7874 -0.4064)
			(stroke
				(width 0.1524)
				(type default)
			)
			(layer "F.SilkS")
		)
		(fp_line
			(start 0.7874 -0.4064)
			(end 0.7874 0.4064)
			(stroke
				(width 0.1524)
				(type default)
			)
			(layer "F.SilkS")
		)
		(fp_line
			(start 0.7874 0.4064)
			(end -0.7874 0.4064)
			(stroke
				(width 0.1524)
				(type default)
			)
			(layer "F.SilkS")
		)
		(fp_line
			(start -0.67945 -0.305054)
			(end -0.12065 -0.305054)
			(stroke
				(width 0.1)
				(type default)
			)
			(layer "F.Fab")
		)
		(fp_line
			(start -0.67945 0.3048)
			(end -0.67945 -0.305054)
			(stroke
				(width 0.1)
				(type default)
			)
			(layer "F.Fab")
		)
		(fp_line
			(start -0.12065 -0.305054)
			(end -0.12065 -0.2794)
			(stroke
				(width 0.1)
				(type default)
			)
			(layer "F.Fab")
		)
		(fp_line
			(start -0.12065 -0.2794)
			(end 0.12065 -0.2794)
			(stroke
				(width 0.1)
				(type default)
			)
			(layer "F.Fab")
		)
		(fp_line
			(start -0.12065 0.2794)
			(end -0.12065 0.3048)
			(stroke
				(width 0.1)
				(type default)
			)
			(layer "F.Fab")
		)
		(fp_line
			(start -0.12065 0.3048)
			(end -0.67945 0.3048)
			(stroke
				(width 0.1)
				(type default)
			)
			(layer "F.Fab")
		)
		(fp_line
			(start 0.120396 0.2794)
			(end -0.12065 0.2794)
			(stroke
				(width 0.1)
				(type default)
			)
			(layer "F.Fab")
		)
		(fp_line
			(start 0.120396 0.3048)
			(end 0.120396 0.2794)
			(stroke
				(width 0.1)
				(type default)
			)
			(layer "F.Fab")
		)
		(fp_line
			(start 0.12065 -0.3048)
			(end 0.67945 -0.3048)
			(stroke
				(width 0.1)
				(type default)
			)
			(layer "F.Fab")
		)
		(fp_line
			(start 0.12065 -0.2794)
			(end 0.12065 -0.3048)
			(stroke
				(width 0.1)
				(type default)
			)
			(layer "F.Fab")
		)
		(fp_line
			(start 0.67945 -0.3048)
			(end 0.67945 0.3048)
			(stroke
				(width 0.1)
				(type default)
			)
			(layer "F.Fab")
		)
		(fp_line
			(start 0.67945 0.3048)
			(end 0.120396 0.3048)
			(stroke
				(width 0.1)
				(type default)
			)
			(layer "F.Fab")
		)
		(pad "1" smd circle
			(at -0.40005 0)
			(size 0 0)
			(layers "F.Cu" "F.Mask" "F.Paste")
			(net "P1V05_PCH_AUX")
		)
		(pad "2" smd circle
			(at 0.40005 0)
			(size 0 0)
			(layers "F.Cu" "F.Mask" "F.Paste")
			(net "FAB_REV_ID0")
		)
	)
)
